(kicad_pcb
	(version 20260206)
	(generator "pcbnew")
	(generator_version "10.0")
	(general
		(thickness 1.6)
		(legacy_teardrops no)
	)
	(paper "A4")
	(title_block
		(title "01162023_DA0F0TEBIF0_F0T_Expander_BD_F_brd_V02_OCP.brd")
		(comment 1 "Grand Teton / footprints 6315-6322 of 9728")
	)
	(layers
		(0 "F.Cu" signal "TOP")
		(4 "In1.Cu" signal "GND")
		(6 "In2.Cu" signal "VCC")
		(8 "In3.Cu" signal "VCC1")
		(10 "In4.Cu" signal "GND1")
		(12 "In5.Cu" signal "IN1")
		(14 "In6.Cu" signal "GND2")
		(16 "In7.Cu" signal "IN2")
		(18 "In8.Cu" signal "GND3")
		(20 "In9.Cu" signal "IN3")
		(22 "In10.Cu" signal "GND4")
		(24 "In11.Cu" signal "IN4")
		(26 "In12.Cu" signal "GND5")
		(28 "In13.Cu" signal "IN5")
		(30 "In14.Cu" signal "GND6")
		(32 "In15.Cu" signal "IN6")
		(34 "In16.Cu" signal "GND7")
		(2 "B.Cu" signal "BOTTOM")
		(9 "F.Adhes" user "F.Adhesive")
		(11 "B.Adhes" user "B.Adhesive")
		(13 "F.Paste" user "Package Geometry/Pastemask Top")
		(15 "B.Paste" user "Package Geometry/Pastemask Bottom")
		(5 "F.SilkS" user "Ref Des/Silkscreen Top")
		(7 "B.SilkS" user "Ref Des/Silkscreen Bottom")
		(1 "F.Mask" user "Board Geometry/Soldermask Top")
		(3 "B.Mask" user "Board Geometry/Soldermask Bottom")
		(17 "Dwgs.User" user "User.Drawings")
		(19 "Cmts.User" user "User.Comments")
		(21 "Eco1.User" user "User.Eco1")
		(23 "Eco2.User" user "User.Eco2")
		(25 "Edge.Cuts" user "Board Geometry/Outline")
		(27 "Margin" user)
		(31 "F.CrtYd" user "Package Geometry/Place Bound Top")
		(29 "B.CrtYd" user "Package Geometry/Place Bound Bottom")
		(35 "F.Fab" user "Ref Des/Assembly Top")
		(33 "B.Fab" user "Ref Des/Assembly Bottom")
	)
	(footprint ""
		(layer "F.Cu")
		(at 434.057806 -299.04055 -90)
		(property "Reference" "C4188"
			(at 0 0 270)
			(layer "F.SilkS")
			(hide yes)
			(effects
				(font
					(size 1.27 1.27)
				)
			)
		)
		(property "Value" ""
			(at 0 0 270)
			(layer "F.Fab")
			(effects
				(font
					(size 1.27 1.27)
				)
			)
		)
		(duplicate_pad_numbers_are_jumpers no)
		(fp_line
			(start -0.7874 0.4064)
			(end -0.7874 -0.4064)
			(stroke
				(width 0.1524)
				(type default)
			)
			(layer "F.SilkS")
		)
		(fp_line
			(start 0.7874 0.4064)
			(end -0.7874 0.4064)
			(stroke
				(width 0.1524)
				(type default)
			)
			(layer "F.SilkS")
		)
		(fp_line
			(start -0.7874 -0.4064)
			(end 0.7874 -0.4064)
			(stroke
				(width 0.1524)
				(type default)
			)
			(layer "F.SilkS")
		)
		(fp_line
			(start 0.7874 -0.4064)
			(end 0.7874 0.4064)
			(stroke
				(width 0.1524)
				(type default)
			)
			(layer "F.SilkS")
		)
		(fp_line
			(start -0.67945 0.3048)
			(end -0.67945 -0.305054)
			(stroke
				(width 0.1)
				(type default)
			)
			(layer "F.Fab")
		)
		(fp_line
			(start -0.12065 0.3048)
			(end -0.67945 0.3048)
			(stroke
				(width 0.1)
				(type default)
			)
			(layer "F.Fab")
		)
		(fp_line
			(start 0.120396 0.3048)
			(end 0.120396 0.2794)
			(stroke
				(width 0.1)
				(type default)
			)
			(layer "F.Fab")
		)
		(fp_line
			(start 0.67945 0.3048)
			(end 0.120396 0.3048)
			(stroke
				(width 0.1)
				(type default)
			)
			(layer "F.Fab")
		)
		(fp_line
			(start -0.12065 0.2794)
			(end -0.12065 0.3048)
			(stroke
				(width 0.1)
				(type default)
			)
			(layer "F.Fab")
		)
		(fp_line
			(start 0.120396 0.2794)
			(end -0.12065 0.2794)
			(stroke
				(width 0.1)
				(type default)
			)
			(layer "F.Fab")
		)
		(fp_line
			(start -0.12065 -0.2794)
			(end 0.12065 -0.2794)
			(stroke
				(width 0.1)
				(type default)
			)
			(layer "F.Fab")
		)
		(fp_line
			(start 0.12065 -0.2794)
			(end 0.12065 -0.3048)
			(stroke
				(width 0.1)
				(type default)
			)
			(layer "F.Fab")
		)
		(fp_line
			(start 0.12065 -0.3048)
			(end 0.67945 -0.3048)
			(stroke
				(width 0.1)
				(type default)
			)
			(layer "F.Fab")
		)
		(fp_line
			(start 0.67945 -0.3048)
			(end 0.67945 0.3048)
			(stroke
				(width 0.1)
				(type default)
			)
			(layer "F.Fab")
		)
		(fp_line
			(start -0.67945 -0.305054)
			(end -0.12065 -0.305054)
			(stroke
				(width 0.1)
				(type default)
			)
			(layer "F.Fab")
		)
		(fp_line
			(start -0.12065 -0.305054)
			(end -0.12065 -0.2794)
			(stroke
				(width 0.1)
				(type default)
			)
			(layer "F.Fab")
		)
		(pad "1" smd circle
			(at -0.40005 0 270)
			(size 0 0)
			(layers "F.Cu" "F.Mask" "F.Paste")
			(net "GND")
		)
		(pad "2" smd circle
			(at 0.40005 0 270)
			(size 0 0)
			(layers "F.Cu" "F.Mask" "F.Paste")
			(net "P1V8_PEX")
		)
	)
	(footprint ""
		(layer "F.Cu")
		(at 95.79229 -29.139642 180)
		(property "Reference" "C95"
			(at 0 0 180)
			(layer "F.SilkS")
			(hide yes)
			(effects
				(font
					(size 1.27 1.27)
				)
			)
		)
		(property "Value" ""
			(at 0 0 180)
			(layer "F.Fab")
			(effects
				(font
					(size 1.27 1.27)
				)
			)
		)
		(duplicate_pad_numbers_are_jumpers no)
		(fp_line
			(start 0.299974 0.150114)
			(end -0.299974 0.150114)
			(stroke
				(width 0.1)
				(type default)
			)
			(layer "F.Fab")
		)
		(fp_line
			(start 0.299974 -0.150114)
			(end 0.299974 0.150114)
			(stroke
				(width 0.1)
				(type default)
			)
			(layer "F.Fab")
		)
		(fp_line
			(start -0.299974 0.150114)
			(end -0.299974 -0.150114)
			(stroke
				(width 0.1)
				(type default)
			)
			(layer "F.Fab")
		)
		(fp_line
			(start -0.299974 -0.150114)
			(end 0.299974 -0.150114)
			(stroke
				(width 0.1)
				(type default)
			)
			(layer "F.Fab")
		)
		(pad "1" smd rect
			(at -0.2667 0 180)
			(size 0.3048 0.381)
			(layers "F.Cu" "F.Mask" "F.Paste")
			(net "P5E_PEX0_STN2_TX_DP<32>")
		)
		(pad "2" smd rect
			(at 0.2667 0 180)
			(size 0.3048 0.381)
			(layers "F.Cu" "F.Mask" "F.Paste")
			(net "P5E_PEX0_STN2_TX_C_DP<32>")
		)
	)
	(footprint ""
		(layer "F.Cu")
		(at 93.350842 -343.952322 90)
		(property "Reference" "C158"
			(at 0 0 90)
			(layer "F.SilkS")
			(hide yes)
			(effects
				(font
					(size 1.27 1.27)
				)
			)
		)
		(property "Value" ""
			(at 0 0 90)
			(layer "F.Fab")
			(effects
				(font
					(size 1.27 1.27)
				)
			)
		)
		(duplicate_pad_numbers_are_jumpers no)
		(fp_line
			(start 0.299974 -0.150114)
			(end 0.299974 0.150114)
			(stroke
				(width 0.1)
				(type default)
			)
			(layer "F.Fab")
		)
		(fp_line
			(start -0.299974 -0.150114)
			(end 0.299974 -0.150114)
			(stroke
				(width 0.1)
				(type default)
			)
			(layer "F.Fab")
		)
		(fp_line
			(start 0.299974 0.150114)
			(end -0.299974 0.150114)
			(stroke
				(width 0.1)
				(type default)
			)
			(layer "F.Fab")
		)
		(fp_line
			(start -0.299974 0.150114)
			(end -0.299974 -0.150114)
			(stroke
				(width 0.1)
				(type default)
			)
			(layer "F.Fab")
		)
		(pad "1" smd rect
			(at -0.2667 0 90)
			(size 0.3048 0.381)
			(layers "F.Cu" "F.Mask" "F.Paste")
			(net "P5E_PEX0_STN6_TX_DN<97>")
		)
		(pad "2" smd rect
			(at 0.2667 0 90)
			(size 0.3048 0.381)
			(layers "F.Cu" "F.Mask" "F.Paste")
			(net "P5E_PEX0_STN6_TX_C_DN<97>")
		)
	)
	(footprint ""
		(layer "F.Cu")
		(at 314.861448 -135.28675 180)
		(property "Reference" "C440"
			(at 0 0 180)
			(layer "F.SilkS")
			(hide yes)
			(effects
				(font
					(size 1.27 1.27)
				)
			)
		)
		(property "Value" ""
			(at 0 0 180)
			(layer "F.Fab")
			(effects
				(font
					(size 1.27 1.27)
				)
			)
		)
		(duplicate_pad_numbers_are_jumpers no)
		(fp_line
			(start 0.299974 0.150114)
			(end -0.299974 0.150114)
			(stroke
				(width 0.1)
				(type default)
			)
			(layer "F.Fab")
		)
		(fp_line
			(start 0.299974 -0.150114)
			(end 0.299974 0.150114)
			(stroke
				(width 0.1)
				(type default)
			)
			(layer "F.Fab")
		)
		(fp_line
			(start -0.299974 0.150114)
			(end -0.299974 -0.150114)
			(stroke
				(width 0.1)
				(type default)
			)
			(layer "F.Fab")
		)
		(fp_line
			(start -0.299974 -0.150114)
			(end 0.299974 -0.150114)
			(stroke
				(width 0.1)
				(type default)
			)
			(layer "F.Fab")
		)
		(pad "1" smd rect
			(at -0.2667 0 180)
			(size 0.3048 0.381)
			(layers "F.Cu" "F.Mask" "F.Paste")
			(net "P5E_PEX2_STN0_TX_DN<7>")
		)
		(pad "2" smd rect
			(at 0.2667 0 180)
			(size 0.3048 0.381)
			(layers "F.Cu" "F.Mask" "F.Paste")
			(net "P5E_PEX2_STN0_TX_C_DN<7>")
		)
	)
	(footprint ""
		(layer "F.Cu")
		(at 319.696084 -388.958836 180)
		(property "Reference" "R1851"
			(at 0 0 180)
			(layer "F.SilkS")
			(hide yes)
			(effects
				(font
					(size 1.27 1.27)
				)
			)
		)
		(property "Value" ""
			(at 0 0 180)
			(layer "F.Fab")
			(effects
				(font
					(size 1.27 1.27)
				)
			)
		)
		(duplicate_pad_numbers_are_jumpers no)
		(fp_line
			(start 0.7874 0.4064)
			(end -0.7874 0.4064)
			(stroke
				(width 0.1524)
				(type default)
			)
			(layer "F.SilkS")
		)
		(fp_line
			(start 0.7874 -0.4064)
			(end 0.7874 0.4064)
			(stroke
				(width 0.1524)
				(type default)
			)
			(layer "F.SilkS")
		)
		(fp_line
			(start -0.7874 0.4064)
			(end -0.7874 -0.4064)
			(stroke
				(width 0.1524)
				(type default)
			)
			(layer "F.SilkS")
		)
		(fp_line
			(start -0.7874 -0.4064)
			(end 0.7874 -0.4064)
			(stroke
				(width 0.1524)
				(type default)
			)
			(layer "F.SilkS")
		)
		(fp_line
			(start 0.67945 0.3048)
			(end 0.120396 0.3048)
			(stroke
				(width 0.1)
				(type default)
			)
			(layer "F.Fab")
		)
		(fp_line
			(start 0.67945 -0.3048)
			(end 0.67945 0.3048)
			(stroke
				(width 0.1)
				(type default)
			)
			(layer "F.Fab")
		)
		(fp_line
			(start 0.12065 -0.2794)
			(end 0.12065 -0.3048)
			(stroke
				(width 0.1)
				(type default)
			)
			(layer "F.Fab")
		)
		(fp_line
			(start 0.12065 -0.3048)
			(end 0.67945 -0.3048)
			(stroke
				(width 0.1)
				(type default)
			)
			(layer "F.Fab")
		)
		(fp_line
			(start 0.120396 0.3048)
			(end 0.120396 0.2794)
			(stroke
				(width 0.1)
				(type default)
			)
			(layer "F.Fab")
		)
		(fp_line
			(start 0.120396 0.2794)
			(end -0.12065 0.2794)
			(stroke
				(width 0.1)
				(type default)
			)
			(layer "F.Fab")
		)
		(fp_line
			(start -0.12065 0.3048)
			(end -0.67945 0.3048)
			(stroke
				(width 0.1)
				(type default)
			)
			(layer "F.Fab")
		)
		(fp_line
			(start -0.12065 0.2794)
			(end -0.12065 0.3048)
			(stroke
				(width 0.1)
				(type default)
			)
			(layer "F.Fab")
		)
		(fp_line
			(start -0.12065 -0.2794)
			(end 0.12065 -0.2794)
			(stroke
				(width 0.1)
				(type default)
			)
			(layer "F.Fab")
		)
		(fp_line
			(start -0.12065 -0.305054)
			(end -0.12065 -0.2794)
			(stroke
				(width 0.1)
				(type default)
			)
			(layer "F.Fab")
		)
		(fp_line
			(start -0.67945 0.3048)
			(end -0.67945 -0.305054)
			(stroke
				(width 0.1)
				(type default)
			)
			(layer "F.Fab")
		)
		(fp_line
			(start -0.67945 -0.305054)
			(end -0.12065 -0.305054)
			(stroke
				(width 0.1)
				(type default)
			)
			(layer "F.Fab")
		)
		(pad "1" smd circle
			(at -0.40005 0 180)
			(size 0 0)
			(layers "F.Cu" "F.Mask" "F.Paste")
			(net "GPU_3V3IO_RSVD5_FFU_R")
		)
		(pad "2" smd circle
			(at 0.40005 0 180)
			(size 0 0)
			(layers "F.Cu" "F.Mask" "F.Paste")
			(net "GPU_3V3IO_RSVD5_FFU")
		)
	)
	(footprint ""
		(layer "F.Cu")
		(at 396.94866 -356.244906 90)
		(property "Reference" "C737"
			(at 0 0 90)
			(layer "F.SilkS")
			(hide yes)
			(effects
				(font
					(size 1.27 1.27)
				)
			)
		)
		(property "Value" ""
			(at 0 0 90)
			(layer "F.Fab")
			(effects
				(font
					(size 1.27 1.27)
				)
			)
		)
		(duplicate_pad_numbers_are_jumpers no)
		(fp_line
			(start 0.299974 -0.150114)
			(end 0.299974 0.150114)
			(stroke
				(width 0.1)
				(type default)
			)
			(layer "F.Fab")
		)
		(fp_line
			(start -0.299974 -0.150114)
			(end 0.299974 -0.150114)
			(stroke
				(width 0.1)
				(type default)
			)
			(layer "F.Fab")
		)
		(fp_line
			(start 0.299974 0.150114)
			(end -0.299974 0.150114)
			(stroke
				(width 0.1)
				(type default)
			)
			(layer "F.Fab")
		)
		(fp_line
			(start -0.299974 0.150114)
			(end -0.299974 -0.150114)
			(stroke
				(width 0.1)
				(type default)
			)
			(layer "F.Fab")
		)
		(pad "1" smd rect
			(at -0.2667 0 90)
			(size 0.3048 0.381)
			(layers "F.Cu" "F.Mask" "F.Paste")
			(net "P5E_PEX3_STN5_TX_DN<92>")
		)
		(pad "2" smd rect
			(at 0.2667 0 90)
			(size 0.3048 0.381)
			(layers "F.Cu" "F.Mask" "F.Paste")
			(net "P5E_PEX3_STN5_TX_C_DN<92>")
		)
	)
	(footprint ""
		(layer "F.Cu")
		(at 352.920554 -87.216234)
		(property "Reference" "R1619"
			(at 0 0 0)
			(layer "F.SilkS")
			(hide yes)
			(effects
				(font
					(size 1.27 1.27)
				)
			)
		)
		(property "Value" ""
			(at 0 0 0)
			(layer "F.Fab")
			(effects
				(font
					(size 1.27 1.27)
				)
			)
		)
		(duplicate_pad_numbers_are_jumpers no)
		(fp_line
			(start -0.7874 -0.4064)
			(end 0.7874 -0.4064)
			(stroke
				(width 0.1524)
				(type default)
			)
			(layer "F.SilkS")
		)
		(fp_line
			(start -0.7874 0.4064)
			(end -0.7874 -0.4064)
			(stroke
				(width 0.1524)
				(type default)
			)
			(layer "F.SilkS")
		)
		(fp_line
			(start 0.7874 -0.4064)
			(end 0.7874 0.4064)
			(stroke
				(width 0.1524)
				(type default)
			)
			(layer "F.SilkS")
		)
		(fp_line
			(start 0.7874 0.4064)
			(end -0.7874 0.4064)
			(stroke
				(width 0.1524)
				(type default)
			)
			(layer "F.SilkS")
		)
		(fp_line
			(start -0.67945 -0.305054)
			(end -0.12065 -0.305054)
			(stroke
				(width 0.1)
				(type default)
			)
			(layer "F.Fab")
		)
		(fp_line
			(start -0.67945 0.3048)
			(end -0.67945 -0.305054)
			(stroke
				(width 0.1)
				(type default)
			)
			(layer "F.Fab")
		)
		(fp_line
			(start -0.12065 -0.305054)
			(end -0.12065 -0.2794)
			(stroke
				(width 0.1)
				(type default)
			)
			(layer "F.Fab")
		)
		(fp_line
			(start -0.12065 -0.2794)
			(end 0.12065 -0.2794)
			(stroke
				(width 0.1)
				(type default)
			)
			(layer "F.Fab")
		)
		(fp_line
			(start -0.12065 0.2794)
			(end -0.12065 0.3048)
			(stroke
				(width 0.1)
				(type default)
			)
			(layer "F.Fab")
		)
		(fp_line
			(start -0.12065 0.3048)
			(end -0.67945 0.3048)
			(stroke
				(width 0.1)
				(type default)
			)
			(layer "F.Fab")
		)
		(fp_line
			(start 0.120396 0.2794)
			(end -0.12065 0.2794)
			(stroke
				(width 0.1)
				(type default)
			)
			(layer "F.Fab")
		)
		(fp_line
			(start 0.120396 0.3048)
			(end 0.120396 0.2794)
			(stroke
				(width 0.1)
				(type default)
			)
			(layer "F.Fab")
		)
		(fp_line
			(start 0.12065 -0.3048)
			(end 0.67945 -0.3048)
			(stroke
				(width 0.1)
				(type default)
			)
			(layer "F.Fab")
		)
		(fp_line
			(start 0.12065 -0.2794)
			(end 0.12065 -0.3048)
			(stroke
				(width 0.1)
				(type default)
			)
			(layer "F.Fab")
		)
		(fp_line
			(start 0.67945 -0.3048)
			(end 0.67945 0.3048)
			(stroke
				(width 0.1)
				(type default)
			)
			(layer "F.Fab")
		)
		(fp_line
			(start 0.67945 0.3048)
			(end 0.120396 0.3048)
			(stroke
				(width 0.1)
				(type default)
			)
			(layer "F.Fab")
		)
		(pad "1" smd circle
			(at -0.40005 0)
			(size 0 0)
			(layers "F.Cu" "F.Mask" "F.Paste")
			(net "SMB_BIC_I2C9_MUX1_SSD9_R_SDA")
		)
		(pad "2" smd circle
			(at 0.40005 0)
			(size 0 0)
			(layers "F.Cu" "F.Mask" "F.Paste")
			(net "SMB_BIC_I2C9_MUX1_SSD9_SDA")
		)
	)
	(footprint ""
		(layer "F.Cu")
		(at 323.917818 -225.929698 180)
		(property "Reference" "R2978"
			(at 0 0 180)
			(layer "F.SilkS")
			(hide yes)
			(effects
				(font
					(size 1.27 1.27)
				)
			)
		)
		(property "Value" ""
			(at 0 0 180)
			(layer "F.Fab")
			(effects
				(font
					(size 1.27 1.27)
				)
			)
		)
		(duplicate_pad_numbers_are_jumpers no)
		(fp_line
			(start 0.7874 0.4064)
			(end -0.7874 0.4064)
			(stroke
				(width 0.1524)
				(type default)
			)
			(layer "F.SilkS")
		)
		(fp_line
			(start 0.7874 -0.4064)
			(end 0.7874 0.4064)
			(stroke
				(width 0.1524)
				(type default)
			)
			(layer "F.SilkS")
		)
		(fp_line
			(start -0.7874 0.4064)
			(end -0.7874 -0.4064)
			(stroke
				(width 0.1524)
				(type default)
			)
			(layer "F.SilkS")
		)
		(fp_line
			(start -0.7874 -0.4064)
			(end 0.7874 -0.4064)
			(stroke
				(width 0.1524)
				(type default)
			)
			(layer "F.SilkS")
		)
		(fp_line
			(start 0.67945 0.3048)
			(end 0.120396 0.3048)
			(stroke
				(width 0.1)
				(type default)
			)
			(layer "F.Fab")
		)
		(fp_line
			(start 0.67945 -0.3048)
			(end 0.67945 0.3048)
			(stroke
				(width 0.1)
				(type default)
			)
			(layer "F.Fab")
		)
		(fp_line
			(start 0.12065 -0.2794)
			(end 0.12065 -0.3048)
			(stroke
				(width 0.1)
				(type default)
			)
			(layer "F.Fab")
		)
		(fp_line
			(start 0.12065 -0.3048)
			(end 0.67945 -0.3048)
			(stroke
				(width 0.1)
				(type default)
			)
			(layer "F.Fab")
		)
		(fp_line
			(start 0.120396 0.3048)
			(end 0.120396 0.2794)
			(stroke
				(width 0.1)
				(type default)
			)
			(layer "F.Fab")
		)
		(fp_line
			(start 0.120396 0.2794)
			(end -0.12065 0.2794)
			(stroke
				(width 0.1)
				(type default)
			)
			(layer "F.Fab")
		)
		(fp_line
			(start -0.12065 0.3048)
			(end -0.67945 0.3048)
			(stroke
				(width 0.1)
				(type default)
			)
			(layer "F.Fab")
		)
		(fp_line
			(start -0.12065 0.2794)
			(end -0.12065 0.3048)
			(stroke
				(width 0.1)
				(type default)
			)
			(layer "F.Fab")
		)
		(fp_line
			(start -0.12065 -0.2794)
			(end 0.12065 -0.2794)
			(stroke
				(width 0.1)
				(type default)
			)
			(layer "F.Fab")
		)
		(fp_line
			(start -0.12065 -0.305054)
			(end -0.12065 -0.2794)
			(stroke
				(width 0.1)
				(type default)
			)
			(layer "F.Fab")
		)
		(fp_line
			(start -0.67945 0.3048)
			(end -0.67945 -0.305054)
			(stroke
				(width 0.1)
				(type default)
			)
			(layer "F.Fab")
		)
		(fp_line
			(start -0.67945 -0.305054)
			(end -0.12065 -0.305054)
			(stroke
				(width 0.1)
				(type default)
			)
			(layer "F.Fab")
		)
		(pad "1" smd circle
			(at -0.40005 0 180)
			(size 0 0)
			(layers "F.Cu" "F.Mask" "F.Paste")
			(net "LED_POSTCODE_0")
		)
		(pad "2" smd circle
			(at 0.40005 0 180)
			(size 0 0)
			(layers "F.Cu" "F.Mask" "F.Paste")
			(net "LED_POSTCODE_R_0")
		)
	)
)
